# S9S_MB_2U (Grand Teton) — schematic netlist excerpt (pin names and nets, part order shuffled) for the footprints in the layout excerpt that follows; sources: Cadence DE-HDL packaged netlist, KiCad conversion of 03242023_DA0F0TMBIJ0_F0T_Motherboard_J_brd_V01_OCP.brd

J1  SCONN288_ADR50017P130CC  SCONN288_ADR50017-P130CC IO  pkg DDR288S_1-1VXB  page 82
  VIN_BULK0  = P12V_S3_AUX_CPU0_NVDIMM
  RFU0  = TP_CHA_CPU0_DIMM1_FRU_0
  VIN_MGMT  = P3V3_AUX
  HSCL  = I3C_SPD_DDRABCD_CPU0_LVC1_SCL_R
  HSDA  = I3C_SPD_DDRABCD_CPU0_LVC1_SDA
  VSS0  = GND
  DQ0_A  = M_A_CPU0_SA_DQ<0>
  VSS1  = GND
  DQ1_A  = M_A_CPU0_SA_DQ<1>
  VSS2  = GND
  DQS0_A_T  = M_A_CPU0_SA_DQS_DP<0>
  DQS0_A_C  = M_A_CPU0_SA_DQS_DN<0>
  VSS3  = GND
  DQ4_A  = M_A_CPU0_SA_DQ<4>
  VSS4  = GND
  DQ5_A  = M_A_CPU0_SA_DQ<5>
  VSS5  = GND
  DQ8_A  = M_A_CPU0_SA_DQ<8>
  VSS6  = GND
  DQ9_A  = M_A_CPU0_SA_DQ<9>
  VSS7  = GND
  DQS1_A_T  = M_A_CPU0_SA_DQS_DP<1>
  DQS1_A_C  = M_A_CPU0_SA_DQS_DN<1>
  VSS8  = GND
  DQ12_A  = M_A_CPU0_SA_DQ<12>
  VSS9  = GND
  DQ13_A  = M_A_CPU0_SA_DQ<13>
  VSS10  = GND
  DQ16_A  = M_A_CPU0_SA_DQ<16>
  VSS11  = GND
  DQ17_A  = M_A_CPU0_SA_DQ<17>
  VSS12  = GND
  DQS2_A_T  = M_A_CPU0_SA_DQS_DP<2>
  DQS2_A_C  = M_A_CPU0_SA_DQS_DN<2>
  VSS13  = GND
  DQ20_A  = M_A_CPU0_SA_DQ<20>
  VSS14  = GND
  DQ21_A  = M_A_CPU0_SA_DQ<21>
  VSS15  = GND
  DQ24_A  = M_A_CPU0_SA_DQ<24>
  VSS16  = GND
  DQ25_A  = M_A_CPU0_SA_DQ<25>
  VSS17  = GND
  DQS3_A_T  = M_A_CPU0_SA_DQS_DP<3>
  DQS3_A_C  = M_A_CPU0_SA_DQS_DN<3>
  VSS18  = GND
  DQ28_A  = M_A_CPU0_SA_DQ<28>
  VSS19  = GND
  DQ29_A  = M_A_CPU0_SA_DQ<29>
  VSS20  = GND
  CB0_A  = M_A_CPU0_SA_CB<0>
  VSS21  = GND
  CB1_A  = M_A_CPU0_SA_CB<1>
  VSS22  = GND
  DQS4_A_T  = M_A_CPU0_SA_DQS_DP<4>
  DQS4_A_C  = M_A_CPU0_SA_DQS_DN<4>
  VSS23  = GND
  CB4_A  = M_A_CPU0_SA_CB<4>
  VSS24  = GND
  CB5_A  = M_A_CPU0_SA_CB<5>
  VSS25  = GND
  ALERT_N  = M_A_CPU0_ALERT_N
  VSS26  = GND
  CS0_A_N  = M_A_CPU0_SA_CS_N<0>
  VSS27  = GND
  CA0_A  = M_A_CPU0_SA_CA<0>
  VSS28  = GND
  CA2_A  = M_A_CPU0_SA_CA<2>
  VSS29  = GND
  CA4_A  = M_A_CPU0_SA_CA<4>
  VSS30  = GND
  CA6_A  = M_A_CPU0_SA_CA<6>
  VSS31  = GND
  PAR_A  = M_A_CPU0_SA_PAR
  VSS32  = GND
  CA0_B  = M_A_CPU0_SB_CA<0>
  VSS33  = GND
  CA2_B  = M_A_CPU0_SB_CA<2>
  VSS34  = GND
  CA4_B  = M_A_CPU0_SB_CA<4>
  VSS35  = GND
  CA6_B  = M_A_CPU0_SB_CA<6>
  VSS36  = GND
  CS0_B_N  = M_A_CPU0_SB_CS_N<0>
  VSS37  = GND
  \lbd||rsp_a_n\  = M_A_CPU0_SA_RSP<0>
  \lbs||rsp_b_n\  = M_A_CPU0_SB_RSP<0>
  VSS38  = GND
  CB4_B  = M_A_CPU0_SB_CB<4>
  VSS39  = GND
  CB5_B  = M_A_CPU0_SB_CB<5>
  VSS40  = GND
  \dqs9_b_t||tdqs9_b_t||dbi4_b_n\  = M_A_CPU0_SB_DQS_DP<9>
  \dqs9_b_c||tdqs9_b_c\  = M_A_CPU0_SB_DQS_DN<9>
  VSS41  = GND
  CB0_B  = M_A_CPU0_SB_CB<0>
  VSS42  = GND
  CB1_B  = M_A_CPU0_SB_CB<1>
  VSS43  = GND
  DQ0_B  = M_A_CPU0_SB_DQ<0>
  VSS44  = GND
  DQ1_B  = M_A_CPU0_SB_DQ<1>
  VSS45  = GND
  DQS0_B_T  = M_A_CPU0_SB_DQS_DP<0>
  DQS0_B_C  = M_A_CPU0_SB_DQS_DN<0>
  VSS46  = GND
  DQ4_B  = M_A_CPU0_SB_DQ<4>
  VSS47  = GND
  DQ5_B  = M_A_CPU0_SB_DQ<5>
  VSS48  = GND
  DQ8_B  = M_A_CPU0_SB_DQ<8>
  VSS49  = GND
  DQ9_B  = M_A_CPU0_SB_DQ<9>
  VSS50  = GND
  DQS1_B_T  = M_A_CPU0_SB_DQS_DP<1>
  DQS1_B_C  = M_A_CPU0_SB_DQS_DN<1>
  VSS51  = GND
  DQ12_B  = M_A_CPU0_SB_DQ<12>
  VSS52  = GND
  DQ13_B  = M_A_CPU0_SB_DQ<13>
  VSS53  = GND
  DQ16_B  = M_A_CPU0_SB_DQ<16>
  VSS54  = GND
  DQ17_B  = M_A_CPU0_SB_DQ<17>
  VSS55  = GND
  DQS2_B_T  = M_A_CPU0_SB_DQS_DP<2>
  DQS2_B_C  = M_A_CPU0_SB_DQS_DN<2>
  VSS56  = GND
  DQ20_B  = M_A_CPU0_SB_DQ<20>
  VSS57  = GND
  DQ21_B  = M_A_CPU0_SB_DQ<21>
  VSS58  = GND
  DQ24_B  = M_A_CPU0_SB_DQ<24>
  VSS59  = GND
  DQ25_B  = M_A_CPU0_SB_DQ<25>
  VSS60  = GND
  DQS3_B_T  = M_A_CPU0_SB_DQS_DP<3>
  DQS3_B_C  = M_A_CPU0_SB_DQS_DN<3>
  VSS61  = GND
  DQ28_B  = M_A_CPU0_SB_DQ<28>
  VSS62  = GND
  DQ29_B  = M_A_CPU0_SB_DQ<29>
  VSS63  = GND
  RFU1  = TP_CHA_CPU0_DIMM1_FRU_1
  VIN_BULK1  = P12V_S3_AUX_CPU0_NVDIMM
  VIN_BULK2  = P12V_S3_AUX_CPU0_NVDIMM
  \pwr_good||fail_n\  = PWRGD_CHA_CPU0_DIMM1
  HSA  = PD_CHA_CPU0_DIMM1_SAA
  RFU2  = TP_CHA_CPU0_DIMM1_FRU_2
  RFU3  = TP_CHA_CPU0_DIMM1_FRU_3
  VSS64  = GND
  DQ2_A  = M_A_CPU0_SA_DQ<2>
  VSS65  = GND
  DQ3_A  = M_A_CPU0_SA_DQ<3>
  VSS66  = GND
  \dqs5_a_c||tdqs5_a_c||dqs5_a_t||tdqs5_a_t\  = M_A_CPU0_SA_DQS_DN<5>
  \dqs5_a_t||tdqs5_a_t\  = M_A_CPU0_SA_DQS_DP<5>
  VSS67  = GND
  DQ6_A  = M_A_CPU0_SA_DQ<6>
  VSS68  = GND
  DQ7_A  = M_A_CPU0_SA_DQ<7>
  VSS69  = GND
  DQ10_A  = M_A_CPU0_SA_DQ<10>
  VSS70  = GND
  DQ11_A  = M_A_CPU0_SA_DQ<11>
  VSS71  = GND
  \dqs6_a_c||tdqs6_a_c||dqs6_a_t||tdqs6_a_t\  = M_A_CPU0_SA_DQS_DN<6>
  \dqs6_a_t||tdqs6_a_t\  = M_A_CPU0_SA_DQS_DP<6>
  VSS72  = GND
  DQ14_A  = M_A_CPU0_SA_DQ<14>
  VSS73  = GND
  DQ15_A  = M_A_CPU0_SA_DQ<15>
  VSS74  = GND
  DQ18_A  = M_A_CPU0_SA_DQ<18>
  VSS75  = GND
  DQ19_A  = M_A_CPU0_SA_DQ<19>
  VSS76  = GND
  \dqs7_a_c||tdqs7_a_c\  = M_A_CPU0_SA_DQS_DN<7>
  \dqs7_a_t||tdqs7_a_t\  = M_A_CPU0_SA_DQS_DP<7>
  VSS77  = GND
  DQ22_A  = M_A_CPU0_SA_DQ<22>
  VSS78  = GND
  DQ23_A  = M_A_CPU0_SA_DQ<23>
  VSS79  = GND
  DQ26_A  = M_A_CPU0_SA_DQ<26>
  VSS80  = GND
  DQ27_A  = M_A_CPU0_SA_DQ<27>
  VSS81  = GND
  \dqs8_a_c||tdqs8_a_c\  = M_A_CPU0_SA_DQS_DN<8>
  \dqs8_a_t||tdqs8_a_t\  = M_A_CPU0_SA_DQS_DP<8>
  VSS82  = GND
  DQ30_A  = M_A_CPU0_SA_DQ<30>
  VSS83  = GND
  DQ31_A  = M_A_CPU0_SA_DQ<31>
  VSS84  = GND
  CB2_A  = M_A_CPU0_SA_CB<2>
  VSS85  = GND
  CB3_A  = M_A_CPU0_SA_CB<3>
  VSS86  = GND
  \dqs9_a_c||tdqs9_a_c\  = M_A_CPU0_SA_DQS_DN<9>
  \dqs9_a_t||tdqs9_a_t\  = M_A_CPU0_SA_DQS_DP<9>
  VSS87  = GND
  CB6_A  = M_A_CPU0_SA_CB<6>
  VSS88  = GND
  CB7_A  = M_A_CPU0_SA_CB<7>
  VSS89  = GND
  RESET_N  = RST_M_AB_CPU0_FPGA_N
  VSS90  = GND
  CS1_A_N  = M_A_CPU0_SA_CS_N<1>
  VSS91  = GND
  CA1_A  = M_A_CPU0_SA_CA<1>
  VSS92  = GND
  CA3_A  = M_A_CPU0_SA_CA<3>
  VSS93  = GND
  CA5_A  = M_A_CPU0_SA_CA<5>
  VSS94  = GND
  CK_T  = M_A_CPU0_CLK_DP<0>
  CK_C  = M_A_CPU0_CLK_DN<0>
  VSS95  = GND
  RFU4  = TP_CHA_CPU0_DIMM1_FRU_4
  CA1_B  = M_A_CPU0_SB_CA<1>
  VSS96  = GND
  CA3_B  = M_A_CPU0_SB_CA<3>
  VSS97  = GND
  CA5_B  = M_A_CPU0_SB_CA<5>
  VSS98  = GND
  PAR_B  = M_A_CPU0_SB_PAR
  VSS99  = GND
  CS1_B_N  = M_A_CPU0_SB_CS_N<1>
  VSS100  = GND
  RFU5  = TP_CHA_CPU0_DIMM1_FRU_5
  RFU6  = TP_CHA_CPU0_DIMM1_FRU_6
  VSS101  = GND
  CB6_B  = M_A_CPU0_SB_CB<6>
  VSS102  = GND
  CB7_B  = M_A_CPU0_SB_CB<7>
  VSS103  = GND
  DQS4_B_C  = M_A_CPU0_SB_DQS_DN<4>
  DQS4_B_T  = M_A_CPU0_SB_DQS_DP<4>
  VSS104  = GND
  CB2_B  = M_A_CPU0_SB_CB<2>
  VSS105  = GND
  CB3_B  = M_A_CPU0_SB_CB<3>
  VSS106  = GND
  DQ2_B  = M_A_CPU0_SB_DQ<2>
  VSS107  = GND
  DQ3_B  = M_A_CPU0_SB_DQ<3>
  VSS108  = GND
  \dqs5_b_c||tdqs5_b_c\  = M_A_CPU0_SB_DQS_DN<5>
  \dqs5_b_t||tdqs5_b_t\  = M_A_CPU0_SB_DQS_DP<5>
  VSS109  = GND
  DQ6_B  = M_A_CPU0_SB_DQ<6>
  VSS110  = GND
  DQ7_B  = M_A_CPU0_SB_DQ<7>
  VSS111  = GND
  DQ10_B  = M_A_CPU0_SB_DQ<10>
  VSS112  = GND
  DQ11_B  = M_A_CPU0_SB_DQ<11>
  VSS113  = GND
  \dqs6_b_c||tdqs6_b_c\  = M_A_CPU0_SB_DQS_DN<6>
  \dqs6_b_t||tdqs6_b_t\  = M_A_CPU0_SB_DQS_DP<6>
  VSS114  = GND
  DQ14_B  = M_A_CPU0_SB_DQ<14>
  VSS115  = GND
  DQ15_B  = M_A_CPU0_SB_DQ<15>
  VSS116  = GND
  DQ18_B  = M_A_CPU0_SB_DQ<18>
  VSS117  = GND
  DQ19_B  = M_A_CPU0_SB_DQ<19>
  VSS118  = GND
  \dqs7_b_c||tdqs7_b_c\  = M_A_CPU0_SB_DQS_DN<7>
  \dqs7_b_t||tdqs7_b_t\  = M_A_CPU0_SB_DQS_DP<7>
  VSS119  = GND
  DQ22_B  = M_A_CPU0_SB_DQ<22>
  VSS120  = GND
  DQ23_B  = M_A_CPU0_SB_DQ<23>
  VSS121  = GND
  DQ26_B  = M_A_CPU0_SB_DQ<26>
  VSS122  = GND
  DQ27_B  = M_A_CPU0_SB_DQ<27>
  VSS123  = GND
  \dqs8_b_c||tdqs8_b_c\  = M_A_CPU0_SB_DQS_DN<8>
  \dqs8_b_t||tdqs8_b_t\  = M_A_CPU0_SB_DQS_DP<8>
  VSS124  = GND
  DQ30_B  = M_A_CPU0_SB_DQ<30>
  VSS125  = GND
  DQ31_B  = M_A_CPU0_SB_DQ<31>
  VSS126  = GND
  G1  = GND
  G2  = GND
  G3  = GND

(kicad_pcb
	(version 20260206)
	(generator "pcbnew")
	(generator_version "10.0")
	(general
		(thickness 1.6)
		(legacy_teardrops no)
	)
	(paper "A4")
	(title_block
		(title "03242023_DA0F0TMBIJ0_F0T_Motherboard_J_brd_V01_OCP.brd")
		(comment 1 "Grand Teton / footprint 1236 of 6105 (J1), pads 229-274 of 291")
	)
	(layers
		(0 "F.Cu" signal "TOP")
		(4 "In1.Cu" signal "GND")
		(6 "In2.Cu" signal "IN1")
		(8 "In3.Cu" signal "GND1")
		(10 "In4.Cu" signal "IN2")
		(12 "In5.Cu" signal "GND2")
		(14 "In6.Cu" signal "IN3")
		(16 "In7.Cu" signal "GND3")
		(18 "In8.Cu" signal "VCC")
		(20 "In9.Cu" signal "VCC1")
		(22 "In10.Cu" signal "GND4")
		(24 "In11.Cu" signal "IN4")
		(26 "In12.Cu" signal "GND5")
		(28 "In13.Cu" signal "IN5")
		(30 "In14.Cu" signal "GND6")
		(32 "In15.Cu" signal "IN6")
		(34 "In16.Cu" signal "GND7")
		(2 "B.Cu" signal "BOTTOM")
		(9 "F.Adhes" user "F.Adhesive")
		(11 "B.Adhes" user "B.Adhesive")
		(13 "F.Paste" user "Package Geometry/Pastemask Top")
		(15 "B.Paste" user "Package Geometry/Pastemask Bottom")
		(5 "F.SilkS" user "Ref Des/Silkscreen Top")
		(7 "B.SilkS" user "Ref Des/Silkscreen Bottom")
		(1 "F.Mask" user "Board Geometry/Soldermask Top")
		(3 "B.Mask" user "Board Geometry/Soldermask Bottom")
		(17 "Dwgs.User" user "User.Drawings")
		(19 "Cmts.User" user "User.Comments")
		(21 "Eco1.User" user "User.Eco1")
		(23 "Eco2.User" user "User.Eco2")
		(25 "Edge.Cuts" user "Board Geometry/Outline")
		(27 "Margin" user)
		(31 "F.CrtYd" user "Package Geometry/Place Bound Top")
		(29 "B.CrtYd" user "Package Geometry/Place Bound Bottom")
		(35 "F.Fab" user "Ref Des/Assembly Top")
		(33 "B.Fab" user "Ref Des/Assembly Bottom")
	)
	(footprint ""
		(layer "F.Cu")
		(at 303.393348 -258.091686)
		(property "Reference" "J1"
			(at -3.683 -81.702148 0)
			(unlocked yes)
			(layer "F.SilkS")
			(effects
				(font
					(size 0.7874 0.5842)
					(thickness 0.1524)
				)
				(justify left)
			)
		)
		(property "Value" ""
			(at 0 0 0)
			(layer "F.Fab")
			(effects
				(font
					(size 1.27 1.27)
				)
			)
		)
		(duplicate_pad_numbers_are_jumpers no)
		(pad "229" smd rect
			(at 2.050034 13.17498 270)
			(size 0.519938 1.4986)
			(layers "F.Cu" "F.Mask" "F.Paste")
			(net "M_A_CPU0_SB_CS_N<1>")
		)
		(pad "230" smd rect
			(at 2.050034 14.025118 270)
			(size 0.519938 1.4986)
			(layers "F.Cu" "F.Mask" "F.Paste")
			(net "GND")
		)
		(pad "231" smd rect
			(at 2.050034 14.875002 270)
			(size 0.519938 1.4986)
			(layers "F.Cu" "F.Mask" "F.Paste")
			(net "TP_CHA_CPU0_DIMM1_FRU_5")
		)
		(pad "232" smd rect
			(at 2.050034 15.724886 270)
			(size 0.519938 1.4986)
			(layers "F.Cu" "F.Mask" "F.Paste")
			(net "TP_CHA_CPU0_DIMM1_FRU_6")
		)
		(pad "233" smd rect
			(at 2.050034 16.575024 270)
			(size 0.519938 1.4986)
			(layers "F.Cu" "F.Mask" "F.Paste")
			(net "GND")
		)
		(pad "234" smd rect
			(at 2.050034 17.424908 270)
			(size 0.519938 1.4986)
			(layers "F.Cu" "F.Mask" "F.Paste")
			(net "M_A_CPU0_SB_CB<6>")
		)
		(pad "235" smd rect
			(at 2.050034 18.275046 270)
			(size 0.519938 1.4986)
			(layers "F.Cu" "F.Mask" "F.Paste")
			(net "GND")
		)
		(pad "236" smd rect
			(at 2.050034 19.12493 270)
			(size 0.519938 1.4986)
			(layers "F.Cu" "F.Mask" "F.Paste")
			(net "M_A_CPU0_SB_CB<7>")
		)
		(pad "237" smd rect
			(at 2.050034 19.975068 270)
			(size 0.519938 1.4986)
			(layers "F.Cu" "F.Mask" "F.Paste")
			(net "GND")
		)
		(pad "238" smd rect
			(at 2.050034 20.824952 270)
			(size 0.519938 1.4986)
			(layers "F.Cu" "F.Mask" "F.Paste")
			(net "M_A_CPU0_SB_DQS_DN<4>")
		)
		(pad "239" smd rect
			(at 2.050034 21.67509 270)
			(size 0.519938 1.4986)
			(layers "F.Cu" "F.Mask" "F.Paste")
			(net "M_A_CPU0_SB_DQS_DP<4>")
		)
		(pad "240" smd rect
			(at 2.050034 22.524974 270)
			(size 0.519938 1.4986)
			(layers "F.Cu" "F.Mask" "F.Paste")
			(net "GND")
		)
		(pad "241" smd rect
			(at 2.050034 23.375112 270)
			(size 0.519938 1.4986)
			(layers "F.Cu" "F.Mask" "F.Paste")
			(net "M_A_CPU0_SB_CB<2>")
		)
		(pad "242" smd rect
			(at 2.050034 24.224996 270)
			(size 0.519938 1.4986)
			(layers "F.Cu" "F.Mask" "F.Paste")
			(net "GND")
		)
		(pad "243" smd rect
			(at 2.050034 25.07488 270)
			(size 0.519938 1.4986)
			(layers "F.Cu" "F.Mask" "F.Paste")
			(net "M_A_CPU0_SB_CB<3>")
		)
		(pad "244" smd rect
			(at 2.050034 25.925018 270)
			(size 0.519938 1.4986)
			(layers "F.Cu" "F.Mask" "F.Paste")
			(net "GND")
		)
		(pad "245" smd rect
			(at 2.050034 26.774902 270)
			(size 0.519938 1.4986)
			(layers "F.Cu" "F.Mask" "F.Paste")
			(net "M_A_CPU0_SB_DQ<2>")
		)
		(pad "246" smd rect
			(at 2.050034 27.62504 270)
			(size 0.519938 1.4986)
			(layers "F.Cu" "F.Mask" "F.Paste")
			(net "GND")
		)
		(pad "247" smd rect
			(at 2.050034 28.474924 270)
			(size 0.519938 1.4986)
			(layers "F.Cu" "F.Mask" "F.Paste")
			(net "M_A_CPU0_SB_DQ<3>")
		)
		(pad "248" smd rect
			(at 2.050034 29.325062 270)
			(size 0.519938 1.4986)
			(layers "F.Cu" "F.Mask" "F.Paste")
			(net "GND")
		)
		(pad "249" smd rect
			(at 2.050034 30.174946 270)
			(size 0.519938 1.4986)
			(layers "F.Cu" "F.Mask" "F.Paste")
			(net "M_A_CPU0_SB_DQS_DN<5>")
		)
		(pad "250" smd rect
			(at 2.050034 31.025084 270)
			(size 0.519938 1.4986)
			(layers "F.Cu" "F.Mask" "F.Paste")
			(net "M_A_CPU0_SB_DQS_DP<5>")
		)
		(pad "251" smd rect
			(at 2.050034 31.874968 270)
			(size 0.519938 1.4986)
			(layers "F.Cu" "F.Mask" "F.Paste")
			(net "GND")
		)
		(pad "252" smd rect
			(at 2.050034 32.725106 270)
			(size 0.519938 1.4986)
			(layers "F.Cu" "F.Mask" "F.Paste")
			(net "M_A_CPU0_SB_DQ<6>")
		)
		(pad "253" smd rect
			(at 2.050034 33.57499 270)
			(size 0.519938 1.4986)
			(layers "F.Cu" "F.Mask" "F.Paste")
			(net "GND")
		)
		(pad "254" smd rect
			(at 2.050034 34.425128 270)
			(size 0.519938 1.4986)
			(layers "F.Cu" "F.Mask" "F.Paste")
			(net "M_A_CPU0_SB_DQ<7>")
		)
		(pad "255" smd rect
			(at 2.050034 35.275012 270)
			(size 0.519938 1.4986)
			(layers "F.Cu" "F.Mask" "F.Paste")
			(net "GND")
		)
		(pad "256" smd rect
			(at 2.050034 36.124896 270)
			(size 0.519938 1.4986)
			(layers "F.Cu" "F.Mask" "F.Paste")
			(net "M_A_CPU0_SB_DQ<10>")
		)
		(pad "257" smd rect
			(at 2.050034 36.975034 270)
			(size 0.519938 1.4986)
			(layers "F.Cu" "F.Mask" "F.Paste")
			(net "GND")
		)
		(pad "258" smd rect
			(at 2.050034 37.824918 270)
			(size 0.519938 1.4986)
			(layers "F.Cu" "F.Mask" "F.Paste")
			(net "M_A_CPU0_SB_DQ<11>")
		)
		(pad "259" smd rect
			(at 2.050034 38.675056 270)
			(size 0.519938 1.4986)
			(layers "F.Cu" "F.Mask" "F.Paste")
			(net "GND")
		)
		(pad "260" smd rect
			(at 2.050034 39.52494 270)
			(size 0.519938 1.4986)
			(layers "F.Cu" "F.Mask" "F.Paste")
			(net "M_A_CPU0_SB_DQS_DN<6>")
		)
		(pad "261" smd rect
			(at 2.050034 40.375078 270)
			(size 0.519938 1.4986)
			(layers "F.Cu" "F.Mask" "F.Paste")
			(net "M_A_CPU0_SB_DQS_DP<6>")
		)
		(pad "262" smd rect
			(at 2.050034 41.224962 270)
			(size 0.519938 1.4986)
			(layers "F.Cu" "F.Mask" "F.Paste")
			(net "GND")
		)
		(pad "263" smd rect
			(at 2.050034 42.0751 270)
			(size 0.519938 1.4986)
			(layers "F.Cu" "F.Mask" "F.Paste")
			(net "M_A_CPU0_SB_DQ<14>")
		)
		(pad "264" smd rect
			(at 2.050034 42.924984 270)
			(size 0.519938 1.4986)
			(layers "F.Cu" "F.Mask" "F.Paste")
			(net "GND")
		)
		(pad "265" smd rect
			(at 2.050034 43.775122 270)
			(size 0.519938 1.4986)
			(layers "F.Cu" "F.Mask" "F.Paste")
			(net "M_A_CPU0_SB_DQ<15>")
		)
		(pad "266" smd rect
			(at 2.050034 44.625006 270)
			(size 0.519938 1.4986)
			(layers "F.Cu" "F.Mask" "F.Paste")
			(net "GND")
		)
		(pad "267" smd rect
			(at 2.050034 45.47489 270)
			(size 0.519938 1.4986)
			(layers "F.Cu" "F.Mask" "F.Paste")
			(net "M_A_CPU0_SB_DQ<18>")
		)
		(pad "268" smd rect
			(at 2.050034 46.325028 270)
			(size 0.519938 1.4986)
			(layers "F.Cu" "F.Mask" "F.Paste")
			(net "GND")
		)
		(pad "269" smd rect
			(at 2.050034 47.174912 270)
			(size 0.519938 1.4986)
			(layers "F.Cu" "F.Mask" "F.Paste")
			(net "M_A_CPU0_SB_DQ<19>")
		)
		(pad "270" smd rect
			(at 2.050034 48.02505 270)
			(size 0.519938 1.4986)
			(layers "F.Cu" "F.Mask" "F.Paste")
			(net "GND")
		)
		(pad "271" smd rect
			(at 2.050034 48.874934 270)
			(size 0.519938 1.4986)
			(layers "F.Cu" "F.Mask" "F.Paste")
			(net "M_A_CPU0_SB_DQS_DN<7>")
		)
		(pad "272" smd rect
			(at 2.050034 49.725072 270)
			(size 0.519938 1.4986)
			(layers "F.Cu" "F.Mask" "F.Paste")
			(net "M_A_CPU0_SB_DQS_DP<7>")
		)
		(pad "273" smd rect
			(at 2.050034 50.574956 270)
			(size 0.519938 1.4986)
			(layers "F.Cu" "F.Mask" "F.Paste")
			(net "GND")
		)
		(pad "274" smd rect
			(at 2.050034 51.425094 270)
			(size 0.519938 1.4986)
			(layers "F.Cu" "F.Mask" "F.Paste")
			(net "M_A_CPU0_SB_DQ<22>")
		)
	)
)
